(kicad_sch (version 20230121) (generator eeschema)

  (paper "A4")

  (title_block
    (title "ECP5 - Datacenter Secure Control Module (DC-SCM)")
    (date "2024-07-15")
    (rev "1.2.1")
  )

  (text "ECP5- Datacenter Secure Control Module (DC-SCM)" (at 86.36 24.765 0)
    (effects (font (size 2.9972 2.9972) (thickness 0.5994) bold) (justify left bottom))
  )

  (symbol (lib_id "antmicroMechanicalParts:oshw_logo") (at 148.59 170.18 0) (unit 1)
    (in_bom yes) (on_board yes) (dnp no)
    (property "Reference" "N2" (at 153.67 168.91 0)
      (effects (font (size 1.27 1.27)) (justify left))
    )
    (property "Value" "oshw_logo" (at 153.67 171.2214 0)
      (effects (font (size 1.27 1.27)) (justify left))
    )
    (property "Footprint" "antmicro-footprints:oshw-logo" (at 149.098 176.276 0)
      (effects (font (size 1.27 1.27)) hide)
    )
    (property "Datasheet" "" (at 148.59 170.18 0)
      (effects (font (size 1.27 1.27)) hide)
    )
    (property "Author" "Antmicro" (at 163.83 185.42 0)
      (effects (font (size 1.27 1.27) (thickness 0.15)) (justify left bottom) hide)
    )
    (property "License" "Apache-2.0" (at 163.83 187.96 0)
      (effects (font (size 1.27 1.27) (thickness 0.15)) (justify left bottom) hide)
    )
    (property "MPN" "" (at 148.59 170.18 0)
      (effects (font (size 1.27 1.27)))
    )
    (property "Manufacturer" "" (at 163.83 190.5 0)
      (effects (font (size 1.27 1.27) (thickness 0.15)) (justify left bottom) hide)
    )
    (property "Public" "False" (at 163.83 190.5 0)
      (effects (font (size 1.27 1.27)) (justify left bottom) hide)
    )
    (instances
      (project "ecp5-dc-scm"
        (path ""
          (reference "N2") (unit 1)
        )
      )
    )
  )

  (symbol (lib_id "antmicroMechanicalParts:antmicro_logo") (at 148.59 177.8 0) (unit 1)
    (in_bom yes) (on_board yes) (dnp no)
    (property "Reference" "N1" (at 154.0256 175.4378 0)
      (effects (font (size 1.27 1.27)) (justify left))
    )
    (property "Value" "antmicro_logo" (at 154.0256 177.7492 0)
      (effects (font (size 1.27 1.27)) (justify left))
    )
    (property "Footprint" "antmicro-footprints:antmicro-logo_scaled_20mm" (at 146.05 171.45 0)
      (effects (font (size 1.27 1.27)) hide)
    )
    (property "Datasheet" "" (at 148.59 168.91 0)
      (effects (font (size 1.27 1.27)) hide)
    )
    (property "MPN" "" (at 148.59 177.8 0)
      (effects (font (size 1.27 1.27)))
    )
    (property "Manufacturer" "" (at 163.83 198.12 0)
      (effects (font (size 1.27 1.27) (thickness 0.15)) (justify left bottom) hide)
    )
    (property "Author" "Antmicro" (at 163.83 193.04 0)
      (effects (font (size 1.27 1.27) (thickness 0.15)) (justify left bottom) hide)
    )
    (property "License" "Apache-2.0" (at 163.83 195.58 0)
      (effects (font (size 1.27 1.27) (thickness 0.15)) (justify left bottom) hide)
    )
    (property "Public" "False" (at 163.83 198.12 0)
      (effects (font (size 1.27 1.27)) (justify left bottom) hide)
    )
    (instances
      (project "ecp5-dc-scm"
        (path ""
          (reference "N1") (unit 1)
        )
      )
    )
  )

  (sheet (at 58.42 135.89) (size 28.575 19.05) (fields_autoplaced)
    (stroke (width 0) (type solid))
    (fill (color 0 0 0 0.0000))
    (property "Sheetname" "PCIe-connector" (at 58.42 135.1784 0)
      (effects (font (size 1.27 1.27)) (justify left bottom))
    )
    (property "Sheetfile" "pcie-conn.kicad_sch" (at 58.42 155.5246 0)
      (effects (font (size 1.27 1.27)) (justify left top))
    )
    (instances
      (project "ecp5-dc-scm"
        (path "" (page "4"))
      )
    )
  )

  (sheet (at 233.045 135.89) (size 28.575 19.05) (fields_autoplaced)
    (stroke (width 0) (type solid))
    (fill (color 0 0 0 0.0000))
    (property "Sheetname" "Power supply" (at 233.045 135.1784 0)
      (effects (font (size 1.27 1.27)) (justify left bottom))
    )
    (property "Sheetfile" "power-supply.kicad_sch" (at 233.045 155.5246 0)
      (effects (font (size 1.27 1.27)) (justify left top))
    )
    (instances
      (project "ecp5-dc-scm"
        (path "" (page "10"))
      )
    )
  )

  (sheet (at 24.13 165.1) (size 47.625 26.035) (fields_autoplaced)
    (stroke (width 0) (type solid))
    (fill (color 0 0 0 0.0000))
    (property "Sheetname" "FPGA power supply" (at 24.13 164.3884 0)
      (effects (font (size 1.27 1.27)) (justify left bottom))
    )
    (property "Sheetfile" "fpga-power-supply.kicad_sch" (at 24.13 191.7196 0)
      (effects (font (size 1.27 1.27)) (justify left top))
    )
    (instances
      (project "ecp5-dc-scm"
        (path "" (page "3"))
      )
    )
  )

  (sheet (at 85.725 165.1) (size 48.26 27.305) (fields_autoplaced)
    (stroke (width 0) (type solid))
    (fill (color 0 0 0 0.0000))
    (property "Sheetname" "FPGA banks" (at 85.725 164.3884 0)
      (effects (font (size 1.27 1.27)) (justify left bottom))
    )
    (property "Sheetfile" "fpga-banks.kicad_sch" (at 85.725 192.9896 0)
      (effects (font (size 1.27 1.27)) (justify left top))
    )
    (instances
      (project "ecp5-dc-scm"
        (path "" (page "5"))
      )
    )
  )

  (sheet (at 200.66 135.89) (size 26.035 18.415) (fields_autoplaced)
    (stroke (width 0) (type solid))
    (fill (color 0 0 0 0.0000))
    (property "Sheetname" "DDR3" (at 200.66 135.1784 0)
      (effects (font (size 1.27 1.27)) (justify left bottom))
    )
    (property "Sheetfile" "ddr3.kicad_sch" (at 200.66 154.8896 0)
      (effects (font (size 1.27 1.27)) (justify left top))
    )
    (instances
      (project "ecp5-dc-scm"
        (path "" (page "9"))
      )
    )
  )

  (sheet (at 24.13 135.89) (size 25.4 18.415) (fields_autoplaced)
    (stroke (width 0) (type solid))
    (fill (color 0 0 0 0.0000))
    (property "Sheetname" "Ethernet" (at 24.13 135.1784 0)
      (effects (font (size 1.27 1.27)) (justify left bottom))
    )
    (property "Sheetfile" "ethernet.kicad_sch" (at 24.13 154.8896 0)
      (effects (font (size 1.27 1.27)) (justify left top))
    )
    (instances
      (project "ecp5-dc-scm"
        (path "" (page "2"))
      )
    )
  )

  (sheet (at 165.735 135.89) (size 27.94 19.05) (fields_autoplaced)
    (stroke (width 0) (type solid))
    (fill (color 0 0 0 0.0000))
    (property "Sheetname" "Interfaces" (at 165.735 135.1784 0)
      (effects (font (size 1.27 1.27)) (justify left bottom))
    )
    (property "Sheetfile" "interfaces.kicad_sch" (at 165.735 155.5246 0)
      (effects (font (size 1.27 1.27)) (justify left top))
    )
    (instances
      (project "ecp5-dc-scm"
        (path "" (page "8"))
      )
    )
  )

  (sheet (at 94.615 135.89) (size 27.94 19.05) (fields_autoplaced)
    (stroke (width 0) (type solid))
    (fill (color 0 0 0 0.0000))
    (property "Sheetname" "RoT" (at 94.615 135.1784 0)
      (effects (font (size 1.27 1.27)) (justify left bottom))
    )
    (property "Sheetfile" "rot.kicad_sch" (at 94.615 155.5246 0)
      (effects (font (size 1.27 1.27)) (justify left top))
    )
    (instances
      (project "ecp5-dc-scm"
        (path "" (page "6"))
      )
    )
  )

  (sheet (at 130.175 135.89) (size 29.21 18.415) (fields_autoplaced)
    (stroke (width 0) (type solid))
    (fill (color 0 0 0 0.0000))
    (property "Sheetname" "Edge connector" (at 130.175 135.1784 0)
      (effects (font (size 1.27 1.27)) (justify left bottom))
    )
    (property "Sheetfile" "edge-connector.kicad_sch" (at 130.175 154.8896 0)
      (effects (font (size 1.27 1.27)) (justify left top))
    )
    (instances
      (project "ecp5-dc-scm"
        (path "" (page "7"))
      )
    )
  )

  (sheet_instances
    (path "/" (page "1"))
  )
)
